FILE_TYPE = CONNECTIVITY;
{Allegro Design Entry HDL 17.2-2016 S081 (4005846) 1/11/2022}
"PAGE_NUMBER" = 277;
0"NC";
END.
